(kicad_pcb
	(version 20260206)
	(generator "pcbnew")
	(generator_version "10.0")
	(general
		(thickness 1.6)
		(legacy_teardrops no)
	)
	(paper "A4")
	(title_block
		(title "Wiwynn_Tioga_Pass_MB.brd")
		(comment 1 "Tioga Pass / footprints 507-513 of 4770")
	)
	(layers
		(0 "F.Cu" signal "TOP")
		(4 "In1.Cu" signal "L2GND")
		(6 "In2.Cu" signal "L3")
		(8 "In3.Cu" signal "L4GND")
		(10 "In4.Cu" signal "L5")
		(12 "In5.Cu" signal "L6GND")
		(14 "In6.Cu" signal "L7VCC")
		(16 "In7.Cu" signal "L8VCC")
		(18 "In8.Cu" signal "L9GND")
		(20 "In9.Cu" signal "L10")
		(22 "In10.Cu" signal "L11GND")
		(24 "In11.Cu" signal "L12")
		(26 "In12.Cu" signal "L13GND")
		(2 "B.Cu" signal "BOTTOM")
		(9 "F.Adhes" user "F.Adhesive")
		(11 "B.Adhes" user "B.Adhesive")
		(13 "F.Paste" user "Package Geometry/Pastemask Top")
		(15 "B.Paste" user "Package Geometry/Pastemask Bottom")
		(5 "F.SilkS" user "Ref Des/Silkscreen Top")
		(7 "B.SilkS" user "Ref Des/Silkscreen Bottom")
		(1 "F.Mask" user "Board Geometry/Soldermask Top")
		(3 "B.Mask" user "Board Geometry/Soldermask Bottom")
		(17 "Dwgs.User" user "User.Drawings")
		(19 "Cmts.User" user "User.Comments")
		(21 "Eco1.User" user "User.Eco1")
		(23 "Eco2.User" user "User.Eco2")
		(25 "Edge.Cuts" user "Board Geometry/Outline")
		(27 "Margin" user)
		(31 "F.CrtYd" user "Package Geometry/Place Bound Top")
		(29 "B.CrtYd" user "Package Geometry/Place Bound Bottom")
		(35 "F.Fab" user "Ref Des/Assembly Top")
		(33 "B.Fab" user "Ref Des/Assembly Bottom")
	)
	(footprint ""
		(layer "F.Cu")
		(at 384.291586 -67.6656 180)
		(property "Reference" "C7E11"
			(at 0 0 180)
			(layer "F.SilkS")
			(hide yes)
			(effects
				(font
					(size 1.27 1.27)
				)
			)
		)
		(property "Value" ""
			(at 0 0 180)
			(layer "F.Fab")
			(effects
				(font
					(size 1.27 1.27)
				)
			)
		)
		(duplicate_pad_numbers_are_jumpers no)
		(fp_line
			(start 0.9017 1.953768)
			(end 0.9017 0.824484)
			(stroke
				(width 0.1524)
				(type default)
			)
			(layer "F.SilkS")
		)
		(fp_line
			(start -0.9017 1.953006)
			(end -0.9017 0.823976)
			(stroke
				(width 0.1524)
				(type default)
			)
			(layer "F.SilkS")
		)
		(fp_poly
			(pts
				(xy -0.9017 -0.3048) (xy 0.9017 -0.3048) (xy 0.9017 3.0988) (xy -0.9017 3.0988)
			)
			(stroke
				(width 0)
				(type default)
			)
			(fill no)
			(layer "F.CrtYd")
		)
		(fp_line
			(start 0.9017 3.0988)
			(end 0.9017 -0.3048)
			(stroke
				(width 0.1)
				(type default)
			)
			(layer "F.Fab")
		)
		(fp_line
			(start 0.9017 -0.3048)
			(end -0.9017 -0.3048)
			(stroke
				(width 0.1)
				(type default)
			)
			(layer "F.Fab")
		)
		(fp_line
			(start -0.9017 3.0988)
			(end 0.9017 3.0988)
			(stroke
				(width 0.1)
				(type default)
			)
			(layer "F.Fab")
		)
		(fp_line
			(start -0.9017 -0.3048)
			(end -0.9017 3.0988)
			(stroke
				(width 0.1)
				(type default)
			)
			(layer "F.Fab")
		)
		(pad "1" smd rect
			(at 0 0 180)
			(size 1.524 1.016)
			(layers "F.Cu" "F.Mask" "F.Paste")
			(net "VR_FET_SW_P5V_STBY_PVIN")
		)
		(pad "2" smd rect
			(at 0 2.794 180)
			(size 1.524 1.016)
			(layers "F.Cu" "F.Mask" "F.Paste")
			(net "GND")
		)
		(zone
			(layer "F.Cu")
			(hatch none 0.5)
			(connect_pads
				(clearance 0)
			)
			(min_thickness 0.25)
			(keepout
				(tracks allowed)
				(vias not_allowed)
				(pads allowed)
				(copperpour not_allowed)
				(footprints allowed)
			)
			(placement
				(enabled no)
				(sheetname "")
			)
			(fill
				(thermal_gap 0.5)
				(thermal_bridge_width 0.5)
				(island_removal_mode 0)
			)
			(polygon
				(pts
					(xy 383.529586 -68.1736) (xy 383.529586 -69.9516) (xy 385.053586 -69.9516) (xy 385.053586 -68.1736)
				)
			)
		)
	)
	(footprint ""
		(layer "F.Cu")
		(at 188.5696 -70.5739 180)
		(property "Reference" "RF5"
			(at -0.8382 -0.67818 180)
			(unlocked yes)
			(layer "F.SilkS")
			(effects
				(font
					(size 0.4064 0.254)
					(thickness 0.1524)
				)
				(justify left)
			)
		)
		(property "Value" ""
			(at 0 0 180)
			(layer "F.Fab")
			(effects
				(font
					(size 1.27 1.27)
				)
			)
		)
		(duplicate_pad_numbers_are_jumpers no)
		(fp_poly
			(pts
				(xy -0.2794 -0.1016) (xy 0.2794 -0.1016) (xy 0.2794 0.9906) (xy -0.2794 0.9906)
			)
			(stroke
				(width 0)
				(type default)
			)
			(fill no)
			(layer "F.CrtYd")
		)
		(fp_line
			(start 0.2794 0.9906)
			(end 0.2794 -0.1016)
			(stroke
				(width 0.1)
				(type default)
			)
			(layer "F.Fab")
		)
		(fp_line
			(start 0.2794 -0.1016)
			(end -0.2794 -0.1016)
			(stroke
				(width 0.1)
				(type default)
			)
			(layer "F.Fab")
		)
		(fp_line
			(start -0.2794 0.9906)
			(end 0.2794 0.9906)
			(stroke
				(width 0.1)
				(type default)
			)
			(layer "F.Fab")
		)
		(fp_line
			(start -0.2794 -0.1016)
			(end -0.2794 0.9906)
			(stroke
				(width 0.1)
				(type default)
			)
			(layer "F.Fab")
		)
		(pad "1" smd rect
			(at 0 0 180)
			(size 0.508 0.508)
			(layers "F.Cu" "F.Mask" "F.Paste")
			(net "VR_PVCCIN_CPU0_AIREF5")
		)
		(pad "2" smd rect
			(at 0 0.889 180)
			(size 0.508 0.508)
			(layers "F.Cu" "F.Mask" "F.Paste")
			(net "ISENSE_PVCCIN_CPU0_PH5_IMON")
		)
		(zone
			(layer "F.Cu")
			(hatch none 0.5)
			(connect_pads
				(clearance 0)
			)
			(min_thickness 0.25)
			(keepout
				(tracks not_allowed)
				(vias allowed)
				(pads allowed)
				(copperpour not_allowed)
				(footprints allowed)
			)
			(placement
				(enabled no)
				(sheetname "")
			)
			(fill
				(thermal_gap 0.5)
				(thermal_bridge_width 0.5)
				(island_removal_mode 0)
			)
			(polygon
				(pts
					(xy 188.8236 -71.2089) (xy 188.3156 -71.2089) (xy 188.3156 -70.8279) (xy 188.8236 -70.8279)
				)
			)
		)
		(zone
			(layer "F.Cu")
			(hatch none 0.5)
			(connect_pads
				(clearance 0)
			)
			(min_thickness 0.25)
			(keepout
				(tracks allowed)
				(vias not_allowed)
				(pads allowed)
				(copperpour not_allowed)
				(footprints allowed)
			)
			(placement
				(enabled no)
				(sheetname "")
			)
			(fill
				(thermal_gap 0.5)
				(thermal_bridge_width 0.5)
				(island_removal_mode 0)
			)
			(polygon
				(pts
					(xy 188.8236 -70.8279) (xy 188.3156 -70.8279) (xy 188.3156 -71.2089) (xy 188.8236 -71.2089)
				)
			)
		)
	)
	(footprint ""
		(layer "F.Cu")
		(at 206.751936 11.952478 -90)
		(property "Reference" "T1P2"
			(at 0 0 270)
			(layer "F.SilkS")
			(hide yes)
			(effects
				(font
					(size 1.27 1.27)
				)
			)
		)
		(property "Value" "*"
			(at -3.302 1.12395 270)
			(unlocked yes)
			(layer "F.Fab")
			(hide yes)
			(effects
				(font
					(size 0.889 0.889)
					(thickness 0.1524)
				)
			)
		)
		(property "Device Type" "TPAD-DIFF-4P-GP_DISCRET-GB3-TPA"
			(at -3.302 -0.40005 270)
			(unlocked yes)
			(layer "F.Fab")
			(hide yes)
			(effects
				(font
					(size 0.889 0.889)
					(thickness 0.1524)
				)
			)
		)
		(duplicate_pad_numbers_are_jumpers no)
		(fp_line
			(start -2.286 2.286)
			(end 2.286 2.286)
			(stroke
				(width 0.1524)
				(type default)
			)
			(layer "F.SilkS")
		)
		(fp_line
			(start 2.286 2.286)
			(end 2.286 -2.286)
			(stroke
				(width 0.1524)
				(type default)
			)
			(layer "F.SilkS")
		)
		(fp_line
			(start -2.286 -2.286)
			(end -2.286 2.286)
			(stroke
				(width 0.1524)
				(type default)
			)
			(layer "F.SilkS")
		)
		(fp_line
			(start 2.286 -2.286)
			(end -2.286 -2.286)
			(stroke
				(width 0.1524)
				(type default)
			)
			(layer "F.SilkS")
		)
		(fp_line
			(start -2.413 -2.413)
			(end -2.413 -1.143)
			(stroke
				(width 0.4064)
				(type default)
			)
			(layer "F.SilkS")
		)
		(fp_line
			(start -1.143 -2.413)
			(end -2.413 -2.413)
			(stroke
				(width 0.4064)
				(type default)
			)
			(layer "F.SilkS")
		)
		(fp_rect
			(start -2.54 2.54)
			(end 2.54 -2.54)
			(stroke
				(width 0)
				(type default)
			)
			(fill no)
			(layer "F.CrtYd")
		)
		(fp_rect
			(start -2.54 2.54)
			(end 2.54 -2.54)
			(stroke
				(width 0)
				(type default)
			)
			(fill no)
			(layer "F.Fab")
		)
		(pad "1" thru_hole circle
			(at -1.27 -1.27 270)
			(size 1.524 1.524)
			(drill 0.9144)
			(layers "*.Cu" "*.Mask")
			(remove_unused_layers no)
			(net "L3_85OHM_6INCH_DP")
			(clearance -0.0508)
			(thermal_gap 0.127)
			(padstack
				(mode front_inner_back)
				(layer "Inner"
					(shape circle)
					(size 1.1684 1.1684)
					(clearance 0.127)
				)
				(layer "B.Cu"
					(shape circle)
					(size 1.524 1.524)
					(clearance -0.0508)
				)
			)
		)
		(pad "2" thru_hole circle
			(at 1.27 -1.27 270)
			(size 1.524 1.524)
			(drill 0.9144)
			(layers "*.Cu" "*.Mask")
			(remove_unused_layers no)
			(net "L3_85OHM_6INCH_DN")
			(clearance -0.0508)
			(thermal_gap 0.127)
			(padstack
				(mode front_inner_back)
				(layer "Inner"
					(shape circle)
					(size 1.1684 1.1684)
					(clearance 0.127)
				)
				(layer "B.Cu"
					(shape circle)
					(size 1.524 1.524)
					(clearance -0.0508)
				)
			)
		)
		(pad "GND1" thru_hole rect
			(at -1.27 1.27 270)
			(size 1.524 1.524)
			(drill 0.9144)
			(layers "*.Cu" "*.Mask")
			(remove_unused_layers no)
			(net "GND")
			(clearance -0.0508)
			(thermal_gap 0.127)
			(padstack
				(mode front_inner_back)
				(layer "Inner"
					(shape circle)
					(size 1.1684 1.1684)
					(clearance 0.127)
				)
				(layer "B.Cu"
					(shape rect)
					(size 1.524 1.524)
					(clearance -0.0508)
				)
			)
		)
		(pad "GND2" thru_hole rect
			(at 1.27 1.27 270)
			(size 1.524 1.524)
			(drill 0.9144)
			(layers "*.Cu" "*.Mask")
			(remove_unused_layers no)
			(net "GND")
			(clearance -0.0508)
			(thermal_gap 0.127)
			(padstack
				(mode front_inner_back)
				(layer "Inner"
					(shape circle)
					(size 1.1684 1.1684)
					(clearance 0.127)
				)
				(layer "B.Cu"
					(shape rect)
					(size 1.524 1.524)
					(clearance -0.0508)
				)
			)
		)
	)
	(footprint ""
		(layer "F.Cu")
		(at 419.316408 -48.064166 180)
		(property "Reference" "R1T23"
			(at -0.8382 -0.67818 180)
			(unlocked yes)
			(layer "F.SilkS")
			(effects
				(font
					(size 0.4064 0.254)
					(thickness 0.1524)
				)
				(justify left)
			)
		)
		(property "Value" ""
			(at 0 0 180)
			(layer "F.Fab")
			(effects
				(font
					(size 1.27 1.27)
				)
			)
		)
		(duplicate_pad_numbers_are_jumpers no)
		(fp_poly
			(pts
				(xy -0.2794 -0.1016) (xy 0.2794 -0.1016) (xy 0.2794 0.9906) (xy -0.2794 0.9906)
			)
			(stroke
				(width 0)
				(type default)
			)
			(fill no)
			(layer "F.CrtYd")
		)
		(fp_line
			(start 0.2794 0.9906)
			(end 0.2794 -0.1016)
			(stroke
				(width 0.1)
				(type default)
			)
			(layer "F.Fab")
		)
		(fp_line
			(start 0.2794 -0.1016)
			(end -0.2794 -0.1016)
			(stroke
				(width 0.1)
				(type default)
			)
			(layer "F.Fab")
		)
		(fp_line
			(start -0.2794 0.9906)
			(end 0.2794 0.9906)
			(stroke
				(width 0.1)
				(type default)
			)
			(layer "F.Fab")
		)
		(fp_line
			(start -0.2794 -0.1016)
			(end -0.2794 0.9906)
			(stroke
				(width 0.1)
				(type default)
			)
			(layer "F.Fab")
		)
		(pad "1" smd rect
			(at 0 0 180)
			(size 0.508 0.508)
			(layers "F.Cu" "F.Mask" "F.Paste")
			(net "FM_BMC_ONCTL_R_N")
		)
		(pad "2" smd rect
			(at 0 0.889 180)
			(size 0.508 0.508)
			(layers "F.Cu" "F.Mask" "F.Paste")
			(net "GND")
		)
		(zone
			(layer "F.Cu")
			(hatch none 0.5)
			(connect_pads
				(clearance 0)
			)
			(min_thickness 0.25)
			(keepout
				(tracks not_allowed)
				(vias allowed)
				(pads allowed)
				(copperpour not_allowed)
				(footprints allowed)
			)
			(placement
				(enabled no)
				(sheetname "")
			)
			(fill
				(thermal_gap 0.5)
				(thermal_bridge_width 0.5)
				(island_removal_mode 0)
			)
			(polygon
				(pts
					(xy 419.570408 -48.699166) (xy 419.062408 -48.699166) (xy 419.062408 -48.318166) (xy 419.570408 -48.318166)
				)
			)
		)
		(zone
			(layer "F.Cu")
			(hatch none 0.5)
			(connect_pads
				(clearance 0)
			)
			(min_thickness 0.25)
			(keepout
				(tracks allowed)
				(vias not_allowed)
				(pads allowed)
				(copperpour not_allowed)
				(footprints allowed)
			)
			(placement
				(enabled no)
				(sheetname "")
			)
			(fill
				(thermal_gap 0.5)
				(thermal_bridge_width 0.5)
				(island_removal_mode 0)
			)
			(polygon
				(pts
					(xy 419.570408 -48.318166) (xy 419.062408 -48.318166) (xy 419.062408 -48.699166) (xy 419.570408 -48.699166)
				)
			)
		)
	)
	(footprint ""
		(layer "F.Cu")
		(at 487.995976 -137.2616 -90)
		(property "Reference" "R1L37"
			(at 0 0 270)
			(layer "F.SilkS")
			(hide yes)
			(effects
				(font
					(size 1.27 1.27)
				)
			)
		)
		(property "Value" ""
			(at 0 0 270)
			(layer "F.Fab")
			(effects
				(font
					(size 1.27 1.27)
				)
			)
		)
		(duplicate_pad_numbers_are_jumpers no)
		(fp_poly
			(pts
				(xy -0.2794 -0.1016) (xy 0.2794 -0.1016) (xy 0.2794 0.9906) (xy -0.2794 0.9906)
			)
			(stroke
				(width 0)
				(type default)
			)
			(fill no)
			(layer "F.CrtYd")
		)
		(fp_line
			(start -0.2794 0.9906)
			(end 0.2794 0.9906)
			(stroke
				(width 0.1)
				(type default)
			)
			(layer "F.Fab")
		)
		(fp_line
			(start 0.2794 0.9906)
			(end 0.2794 -0.1016)
			(stroke
				(width 0.1)
				(type default)
			)
			(layer "F.Fab")
		)
		(fp_line
			(start -0.2794 -0.1016)
			(end -0.2794 0.9906)
			(stroke
				(width 0.1)
				(type default)
			)
			(layer "F.Fab")
		)
		(fp_line
			(start 0.2794 -0.1016)
			(end -0.2794 -0.1016)
			(stroke
				(width 0.1)
				(type default)
			)
			(layer "F.Fab")
		)
		(pad "1" smd rect
			(at 0 0 270)
			(size 0.508 0.508)
			(layers "F.Cu" "F.Mask" "F.Paste")
			(net "P5V_STBY")
		)
		(pad "2" smd rect
			(at 0 0.889 270)
			(size 0.508 0.508)
			(layers "F.Cu" "F.Mask" "F.Paste")
			(net "LED_P5V_STBY")
		)
		(zone
			(layer "F.Cu")
			(hatch none 0.5)
			(connect_pads
				(clearance 0)
			)
			(min_thickness 0.25)
			(keepout
				(tracks not_allowed)
				(vias allowed)
				(pads allowed)
				(copperpour not_allowed)
				(footprints allowed)
			)
			(placement
				(enabled no)
				(sheetname "")
			)
			(fill
				(thermal_gap 0.5)
				(thermal_bridge_width 0.5)
				(island_removal_mode 0)
			)
			(polygon
				(pts
					(xy 487.360976 -137.5156) (xy 487.360976 -137.0076) (xy 487.741976 -137.0076) (xy 487.741976 -137.5156)
				)
			)
		)
		(zone
			(layer "F.Cu")
			(hatch none 0.5)
			(connect_pads
				(clearance 0)
			)
			(min_thickness 0.25)
			(keepout
				(tracks allowed)
				(vias not_allowed)
				(pads allowed)
				(copperpour not_allowed)
				(footprints allowed)
			)
			(placement
				(enabled no)
				(sheetname "")
			)
			(fill
				(thermal_gap 0.5)
				(thermal_bridge_width 0.5)
				(island_removal_mode 0)
			)
			(polygon
				(pts
					(xy 487.741976 -137.5156) (xy 487.741976 -137.0076) (xy 487.360976 -137.0076) (xy 487.360976 -137.5156)
				)
			)
		)
	)
	(footprint ""
		(layer "F.Cu")
		(at 19.088608 -1.07696 -90)
		(property "Reference" "R1G20"
			(at 0 0 270)
			(layer "F.SilkS")
			(hide yes)
			(effects
				(font
					(size 1.27 1.27)
				)
			)
		)
		(property "Value" ""
			(at 0 0 270)
			(layer "F.Fab")
			(effects
				(font
					(size 1.27 1.27)
				)
			)
		)
		(duplicate_pad_numbers_are_jumpers no)
		(fp_rect
			(start 0.4953 1.6002)
			(end -0.4953 -0.2032)
			(stroke
				(width 0)
				(type default)
			)
			(fill no)
			(layer "F.CrtYd")
		)
		(fp_line
			(start -0.4953 1.6002)
			(end -0.4953 -0.2032)
			(stroke
				(width 0.1)
				(type default)
			)
			(layer "F.Fab")
		)
		(fp_line
			(start 0.4953 1.6002)
			(end -0.4953 1.6002)
			(stroke
				(width 0.1)
				(type default)
			)
			(layer "F.Fab")
		)
		(fp_line
			(start -0.4953 -0.2032)
			(end 0.4953 -0.2032)
			(stroke
				(width 0.1)
				(type default)
			)
			(layer "F.Fab")
		)
		(fp_line
			(start 0.4953 -0.2032)
			(end 0.4953 1.6002)
			(stroke
				(width 0.1)
				(type default)
			)
			(layer "F.Fab")
		)
		(pad "1" smd rect
			(at 0 0 270)
			(size 0.762 0.889)
			(layers "F.Cu" "F.Mask" "F.Paste")
			(net "PVDDQ_GHJ")
		)
		(pad "2" smd rect
			(at 0 1.397 270)
			(size 0.762 0.889)
			(layers "F.Cu" "F.Mask" "F.Paste")
			(net "GND")
		)
		(zone
			(layer "F.Cu")
			(hatch none 0.5)
			(connect_pads
				(clearance 0)
			)
			(min_thickness 0.25)
			(keepout
				(tracks not_allowed)
				(vias allowed)
				(pads allowed)
				(copperpour not_allowed)
				(footprints allowed)
			)
			(placement
				(enabled no)
				(sheetname "")
			)
			(fill
				(thermal_gap 0.5)
				(thermal_bridge_width 0.5)
				(island_removal_mode 0)
			)
			(polygon
				(pts
					(xy 18.136108 -0.69596) (xy 18.644108 -0.69596) (xy 18.644108 -1.45796) (xy 18.136108 -1.45796)
				)
			)
		)
		(zone
			(layer "F.Cu")
			(hatch none 0.5)
			(connect_pads
				(clearance 0)
			)
			(min_thickness 0.25)
			(keepout
				(tracks allowed)
				(vias not_allowed)
				(pads allowed)
				(copperpour not_allowed)
				(footprints allowed)
			)
			(placement
				(enabled no)
				(sheetname "")
			)
			(fill
				(thermal_gap 0.5)
				(thermal_bridge_width 0.5)
				(island_removal_mode 0)
			)
			(polygon
				(pts
					(xy 18.136108 -0.69596) (xy 18.644108 -0.69596) (xy 18.644108 -1.45796) (xy 18.136108 -1.45796)
				)
			)
		)
	)
	(footprint ""
		(layer "F.Cu")
		(at 38.965886 -85.6996 -90)
		(property "Reference" "CT14"
			(at -0.8382 -0.67818 270)
			(unlocked yes)
			(layer "F.SilkS")
			(effects
				(font
					(size 0.4064 0.254)
					(thickness 0.1524)
				)
				(justify left)
			)
		)
		(property "Value" ""
			(at 0 0 270)
			(layer "F.Fab")
			(effects
				(font
					(size 1.27 1.27)
				)
			)
		)
		(duplicate_pad_numbers_are_jumpers no)
		(fp_poly
			(pts
				(xy 0.3048 -0.1016) (xy 0.3048 0.9906) (xy -0.3048 0.9906) (xy -0.3048 -0.1016)
			)
			(stroke
				(width 0)
				(type default)
			)
			(fill no)
			(layer "F.CrtYd")
		)
		(fp_line
			(start -0.3048 0.9906)
			(end 0.3048 0.9906)
			(stroke
				(width 0.1)
				(type default)
			)
			(layer "F.Fab")
		)
		(fp_line
			(start 0.3048 0.9906)
			(end 0.3048 -0.1016)
			(stroke
				(width 0.1)
				(type default)
			)
			(layer "F.Fab")
		)
		(fp_line
			(start -0.3048 -0.1016)
			(end -0.3048 0.9906)
			(stroke
				(width 0.1)
				(type default)
			)
			(layer "F.Fab")
		)
		(fp_line
			(start 0.3048 -0.1016)
			(end -0.3048 -0.1016)
			(stroke
				(width 0.1)
				(type default)
			)
			(layer "F.Fab")
		)
		(pad "1" smd rect
			(at 0 0 270)
			(size 0.508 0.508)
			(layers "F.Cu" "F.Mask" "F.Paste")
			(net "VR_PVCCIN_CPU1_PHASE5")
		)
		(pad "2" smd rect
			(at 0 0.889 270)
			(size 0.508 0.508)
			(layers "F.Cu" "F.Mask" "F.Paste")
			(net "VR_PVCCIN_CPU1_PHASE5_RC")
		)
		(zone
			(layer "F.Cu")
			(hatch none 0.5)
			(connect_pads
				(clearance 0)
			)
			(min_thickness 0.25)
			(keepout
				(tracks not_allowed)
				(vias allowed)
				(pads allowed)
				(copperpour not_allowed)
				(footprints allowed)
			)
			(placement
				(enabled no)
				(sheetname "")
			)
			(fill
				(thermal_gap 0.5)
				(thermal_bridge_width 0.5)
				(island_removal_mode 0)
			)
			(polygon
				(pts
					(xy 38.330886 -85.9536) (xy 38.330886 -85.4456) (xy 38.711886 -85.4456) (xy 38.711886 -85.9536)
				)
			)
		)
		(zone
			(layer "F.Cu")
			(hatch none 0.5)
			(connect_pads
				(clearance 0)
			)
			(min_thickness 0.25)
			(keepout
				(tracks allowed)
				(vias not_allowed)
				(pads allowed)
				(copperpour not_allowed)
				(footprints allowed)
			)
			(placement
				(enabled no)
				(sheetname "")
			)
			(fill
				(thermal_gap 0.5)
				(thermal_bridge_width 0.5)
				(island_removal_mode 0)
			)
			(polygon
				(pts
					(xy 38.711886 -85.9536) (xy 38.711886 -85.4456) (xy 38.330886 -85.4456) (xy 38.330886 -85.9536)
				)
			)
		)
	)
)
